# BASEBOARD_FAB2 (Tioga Pass) — schematic netlist excerpt (pin names and nets, part order shuffled) for the footprints in the layout excerpt that follows; sources: Cadence DE-HDL packaged netlist, KiCad conversion of Wiwynn_Tioga_Pass_MB.brd

R25W78  RES  22.1 1.0% CHIP  pkg 0402  page 146 : A = SPI_BMC_BT_CS_R_N ; B = SPI_BMC_BT_CS_N
C5A14  CAP_A  47UF 4V 20% X5R  pkg 0603V  page 220 : A = PVDDQ_DEF ; B = GND
R8E35  RES  0.0 5% CHIP  pkg 0402  page 240 : A = VR_P3V3_STBY_BOOT ; B = VR_P3V3_STBY_BOOT_R

(kicad_pcb
	(version 20260206)
	(generator "pcbnew")
	(generator_version "10.0")
	(general
		(thickness 1.6)
		(legacy_teardrops no)
	)
	(paper "A4")
	(title_block
		(title "Wiwynn_Tioga_Pass_MB.brd")
		(comment 1 "Tioga Pass / footprints 250-252 of 4770")
	)
	(layers
		(0 "F.Cu" signal "TOP")
		(4 "In1.Cu" signal "L2GND")
		(6 "In2.Cu" signal "L3")
		(8 "In3.Cu" signal "L4GND")
		(10 "In4.Cu" signal "L5")
		(12 "In5.Cu" signal "L6GND")
		(14 "In6.Cu" signal "L7VCC")
		(16 "In7.Cu" signal "L8VCC")
		(18 "In8.Cu" signal "L9GND")
		(20 "In9.Cu" signal "L10")
		(22 "In10.Cu" signal "L11GND")
		(24 "In11.Cu" signal "L12")
		(26 "In12.Cu" signal "L13GND")
		(2 "B.Cu" signal "BOTTOM")
		(9 "F.Adhes" user "F.Adhesive")
		(11 "B.Adhes" user "B.Adhesive")
		(13 "F.Paste" user "Package Geometry/Pastemask Top")
		(15 "B.Paste" user "Package Geometry/Pastemask Bottom")
		(5 "F.SilkS" user "Ref Des/Silkscreen Top")
		(7 "B.SilkS" user "Ref Des/Silkscreen Bottom")
		(1 "F.Mask" user "Board Geometry/Soldermask Top")
		(3 "B.Mask" user "Board Geometry/Soldermask Bottom")
		(17 "Dwgs.User" user "User.Drawings")
		(19 "Cmts.User" user "User.Comments")
		(21 "Eco1.User" user "User.Eco1")
		(23 "Eco2.User" user "User.Eco2")
		(25 "Edge.Cuts" user "Board Geometry/Outline")
		(27 "Margin" user)
		(31 "F.CrtYd" user "Package Geometry/Place Bound Top")
		(29 "B.CrtYd" user "Package Geometry/Place Bound Bottom")
		(35 "F.Fab" user "Ref Des/Assembly Top")
		(33 "B.Fab" user "Ref Des/Assembly Bottom")
	)
	(footprint ""
		(layer "F.Cu")
		(at 253.392432 -140.208 90)
		(property "Reference" "C5A14"
			(at 1.848866 0.752348 90)
			(unlocked yes)
			(layer "F.SilkS")
			(effects
				(font
					(size 1.27 0.9652)
					(thickness 0.1524)
				)
			)
		)
		(property "Value" ""
			(at 0 0 90)
			(layer "F.Fab")
			(effects
				(font
					(size 1.27 1.27)
				)
			)
		)
		(duplicate_pad_numbers_are_jumpers no)
		(fp_rect
			(start -0.500126 1.598422)
			(end 0.500126 -0.201422)
			(stroke
				(width 0)
				(type default)
			)
			(fill no)
			(layer "F.CrtYd")
		)
		(fp_line
			(start 0.500126 -0.201422)
			(end 0.500126 1.598422)
			(stroke
				(width 0.1)
				(type default)
			)
			(layer "F.Fab")
		)
		(fp_line
			(start -0.500126 -0.201422)
			(end 0.500126 -0.201422)
			(stroke
				(width 0.1)
				(type default)
			)
			(layer "F.Fab")
		)
		(fp_line
			(start 0.500126 1.598422)
			(end -0.500126 1.598422)
			(stroke
				(width 0.1)
				(type default)
			)
			(layer "F.Fab")
		)
		(fp_line
			(start -0.500126 1.598422)
			(end -0.500126 -0.201422)
			(stroke
				(width 0.1)
				(type default)
			)
			(layer "F.Fab")
		)
		(pad "1" smd rect
			(at 0 0)
			(size 0.889 0.9906)
			(layers "F.Cu" "F.Mask" "F.Paste")
			(net "PVDDQ_DEF")
		)
		(pad "2" smd rect
			(at 0 1.397)
			(size 0.889 0.9906)
			(layers "F.Cu" "F.Mask" "F.Paste")
			(net "GND")
		)
		(zone
			(layer "F.Cu")
			(hatch none 0.5)
			(connect_pads
				(clearance 0)
			)
			(min_thickness 0.25)
			(keepout
				(tracks allowed)
				(vias not_allowed)
				(pads allowed)
				(copperpour not_allowed)
				(footprints allowed)
			)
			(placement
				(enabled no)
				(sheetname "")
			)
			(fill
				(thermal_gap 0.5)
				(thermal_bridge_width 0.5)
				(island_removal_mode 0)
			)
			(polygon
				(pts
					(xy 254.344932 -139.7127) (xy 254.344932 -140.7033) (xy 253.836932 -140.7033) (xy 253.836932 -139.7127)
				)
			)
		)
		(zone
			(layer "F.Cu")
			(hatch none 0.5)
			(connect_pads
				(clearance 0)
			)
			(min_thickness 0.25)
			(keepout
				(tracks not_allowed)
				(vias allowed)
				(pads allowed)
				(copperpour not_allowed)
				(footprints allowed)
			)
			(placement
				(enabled no)
				(sheetname "")
			)
			(fill
				(thermal_gap 0.5)
				(thermal_bridge_width 0.5)
				(island_removal_mode 0)
			)
			(polygon
				(pts
					(xy 254.344932 -139.7127) (xy 254.344932 -140.7033) (xy 253.836932 -140.7033) (xy 253.836932 -139.7127)
				)
			)
		)
	)
	(footprint ""
		(layer "F.Cu")
		(at 427.56836 -45.872654)
		(property "Reference" "R25W78"
			(at -0.8382 -0.67818 0)
			(unlocked yes)
			(layer "F.SilkS")
			(effects
				(font
					(size 0.4064 0.254)
					(thickness 0.1524)
				)
				(justify left)
			)
		)
		(property "Value" ""
			(at 0 0 0)
			(layer "F.Fab")
			(effects
				(font
					(size 1.27 1.27)
				)
			)
		)
		(duplicate_pad_numbers_are_jumpers no)
		(fp_poly
			(pts
				(xy -0.2794 -0.1016) (xy 0.2794 -0.1016) (xy 0.2794 0.9906) (xy -0.2794 0.9906)
			)
			(stroke
				(width 0)
				(type default)
			)
			(fill no)
			(layer "F.CrtYd")
		)
		(fp_line
			(start -0.2794 -0.1016)
			(end -0.2794 0.9906)
			(stroke
				(width 0.1)
				(type default)
			)
			(layer "F.Fab")
		)
		(fp_line
			(start -0.2794 0.9906)
			(end 0.2794 0.9906)
			(stroke
				(width 0.1)
				(type default)
			)
			(layer "F.Fab")
		)
		(fp_line
			(start 0.2794 -0.1016)
			(end -0.2794 -0.1016)
			(stroke
				(width 0.1)
				(type default)
			)
			(layer "F.Fab")
		)
		(fp_line
			(start 0.2794 0.9906)
			(end 0.2794 -0.1016)
			(stroke
				(width 0.1)
				(type default)
			)
			(layer "F.Fab")
		)
		(pad "1" smd rect
			(at 0 0)
			(size 0.508 0.508)
			(layers "F.Cu" "F.Mask" "F.Paste")
			(net "SPI_BMC_BT_CS_R_N")
		)
		(pad "2" smd rect
			(at 0 0.889)
			(size 0.508 0.508)
			(layers "F.Cu" "F.Mask" "F.Paste")
			(net "SPI_BMC_BT_CS_N")
		)
		(zone
			(layer "F.Cu")
			(hatch none 0.5)
			(connect_pads
				(clearance 0)
			)
			(min_thickness 0.25)
			(keepout
				(tracks allowed)
				(vias not_allowed)
				(pads allowed)
				(copperpour not_allowed)
				(footprints allowed)
			)
			(placement
				(enabled no)
				(sheetname "")
			)
			(fill
				(thermal_gap 0.5)
				(thermal_bridge_width 0.5)
				(island_removal_mode 0)
			)
			(polygon
				(pts
					(xy 427.31436 -45.618654) (xy 427.82236 -45.618654) (xy 427.82236 -45.237654) (xy 427.31436 -45.237654)
				)
			)
		)
		(zone
			(layer "F.Cu")
			(hatch none 0.5)
			(connect_pads
				(clearance 0)
			)
			(min_thickness 0.25)
			(keepout
				(tracks not_allowed)
				(vias allowed)
				(pads allowed)
				(copperpour not_allowed)
				(footprints allowed)
			)
			(placement
				(enabled no)
				(sheetname "")
			)
			(fill
				(thermal_gap 0.5)
				(thermal_bridge_width 0.5)
				(island_removal_mode 0)
			)
			(polygon
				(pts
					(xy 427.31436 -45.237654) (xy 427.82236 -45.237654) (xy 427.82236 -45.618654) (xy 427.31436 -45.618654)
				)
			)
		)
	)
	(footprint ""
		(layer "F.Cu")
		(at 468.112856 -25.762204 180)
		(property "Reference" "R8E35"
			(at 0 0 180)
			(layer "F.SilkS")
			(hide yes)
			(effects
				(font
					(size 1.27 1.27)
				)
			)
		)
		(property "Value" ""
			(at 0 0 180)
			(layer "F.Fab")
			(effects
				(font
					(size 1.27 1.27)
				)
			)
		)
		(duplicate_pad_numbers_are_jumpers no)
		(fp_rect
			(start 0.2794 -0.1016)
			(end -0.2794 0.9906)
			(stroke
				(width 0)
				(type default)
			)
			(fill no)
			(layer "F.CrtYd")
		)
		(fp_line
			(start 0.2794 0.9906)
			(end 0.2794 -0.1016)
			(stroke
				(width 0.1)
				(type default)
			)
			(layer "F.Fab")
		)
		(fp_line
			(start 0.2794 -0.1016)
			(end -0.2794 -0.1016)
			(stroke
				(width 0.1)
				(type default)
			)
			(layer "F.Fab")
		)
		(fp_line
			(start -0.2794 0.9906)
			(end 0.2794 0.9906)
			(stroke
				(width 0.1)
				(type default)
			)
			(layer "F.Fab")
		)
		(fp_line
			(start -0.2794 -0.1016)
			(end -0.2794 0.9906)
			(stroke
				(width 0.1)
				(type default)
			)
			(layer "F.Fab")
		)
		(pad "1" smd rect
			(at 0 0 180)
			(size 0.508 0.508)
			(layers "F.Cu" "F.Mask" "F.Paste")
			(net "VR_P3V3_STBY_BOOT")
		)
		(pad "2" smd rect
			(at 0 0.889 180)
			(size 0.508 0.508)
			(layers "F.Cu" "F.Mask" "F.Paste")
			(net "VR_P3V3_STBY_BOOT_R")
		)
		(zone
			(layer "F.Cu")
			(hatch none 0.5)
			(connect_pads
				(clearance 0)
			)
			(min_thickness 0.25)
			(keepout
				(tracks not_allowed)
				(vias allowed)
				(pads allowed)
				(copperpour not_allowed)
				(footprints allowed)
			)
			(placement
				(enabled no)
				(sheetname "")
			)
			(fill
				(thermal_gap 0.5)
				(thermal_bridge_width 0.5)
				(island_removal_mode 0)
			)
			(polygon
				(pts
					(xy 467.858856 -26.016204) (xy 468.366856 -26.016204) (xy 468.366856 -26.397204) (xy 467.858856 -26.397204)
				)
			)
		)
		(zone
			(layer "F.Cu")
			(hatch none 0.5)
			(connect_pads
				(clearance 0)
			)
			(min_thickness 0.25)
			(keepout
				(tracks allowed)
				(vias not_allowed)
				(pads allowed)
				(copperpour not_allowed)
				(footprints allowed)
			)
			(placement
				(enabled no)
				(sheetname "")
			)
			(fill
				(thermal_gap 0.5)
				(thermal_bridge_width 0.5)
				(island_removal_mode 0)
			)
			(polygon
				(pts
					(xy 467.858856 -26.016204) (xy 468.366856 -26.016204) (xy 468.366856 -26.397204) (xy 467.858856 -26.397204)
				)
			)
		)
	)
)
